# T6G (Grand Teton) — schematic netlist excerpt (pin names and nets, part order shuffled) for the footprints in the layout excerpt that follows; sources: Cadence DE-HDL packaged netlist, KiCad conversion of 04192023_DAF0TMB3IC0_F0TG_MB_C_brd_V02_OCP.brd

R2991  Q_RES  33.2 1% CHIP  pkg 0402LF  page 248 : A = SMB_2_BMC_GPU_BUF_R_SDA ; B = SMB_2_BMC_GPU_BUF_SDA
R4061  Q_RES  0 5% EMPTY  pkg 0402LF  page 134 : A = P12V_OCP_SFF_EN_R ; B = P12V_OCP_EN_1_R

(kicad_pcb
	(version 20260206)
	(generator "pcbnew")
	(generator_version "10.0")
	(general
		(thickness 1.6)
		(legacy_teardrops no)
	)
	(paper "A4")
	(title_block
		(title "04192023_DAF0TMB3IC0_F0TG_MB_C_brd_V02_OCP.brd")
		(comment 1 "Grand Teton / footprints 3136-3137 of 8354")
	)
	(layers
		(0 "F.Cu" signal "TOP")
		(4 "In1.Cu" signal "GND")
		(6 "In2.Cu" signal "IN1")
		(8 "In3.Cu" signal "GND1")
		(10 "In4.Cu" signal "IN2")
		(12 "In5.Cu" signal "GND2")
		(14 "In6.Cu" signal "IN3")
		(16 "In7.Cu" signal "GND3")
		(18 "In8.Cu" signal "VCC")
		(20 "In9.Cu" signal "VCC1")
		(22 "In10.Cu" signal "GND4")
		(24 "In11.Cu" signal "IN4")
		(26 "In12.Cu" signal "GND5")
		(28 "In13.Cu" signal "IN5")
		(30 "In14.Cu" signal "GND6")
		(32 "In15.Cu" signal "IN6")
		(34 "In16.Cu" signal "GND7")
		(2 "B.Cu" signal "BOTTOM")
		(9 "F.Adhes" user "F.Adhesive")
		(11 "B.Adhes" user "B.Adhesive")
		(13 "F.Paste" user "Package Geometry/Pastemask Top")
		(15 "B.Paste" user "Package Geometry/Pastemask Bottom")
		(5 "F.SilkS" user "Ref Des/Silkscreen Top")
		(7 "B.SilkS" user "Ref Des/Silkscreen Bottom")
		(1 "F.Mask" user "Board Geometry/Soldermask Top")
		(3 "B.Mask" user "Board Geometry/Soldermask Bottom")
		(17 "Dwgs.User" user "User.Drawings")
		(19 "Cmts.User" user "User.Comments")
		(21 "Eco1.User" user "User.Eco1")
		(23 "Eco2.User" user "User.Eco2")
		(25 "Edge.Cuts" user "Board Geometry/Outline")
		(27 "Margin" user)
		(31 "F.CrtYd" user "Package Geometry/Place Bound Top")
		(29 "B.CrtYd" user "Package Geometry/Place Bound Bottom")
		(35 "F.Fab" user "Ref Des/Assembly Top")
		(33 "B.Fab" user "Ref Des/Assembly Bottom")
	)
	(footprint ""
		(layer "F.Cu")
		(at 468.957914 -42.121836 180)
		(property "Reference" "R4061"
			(at 0 0 180)
			(layer "F.SilkS")
			(hide yes)
			(effects
				(font
					(size 1.27 1.27)
				)
			)
		)
		(property "Value" ""
			(at 0 0 180)
			(layer "F.Fab")
			(effects
				(font
					(size 1.27 1.27)
				)
			)
		)
		(duplicate_pad_numbers_are_jumpers no)
		(fp_line
			(start 0.7874 0.4064)
			(end -0.7874 0.4064)
			(stroke
				(width 0.1524)
				(type default)
			)
			(layer "F.SilkS")
		)
		(fp_line
			(start 0.7874 -0.4064)
			(end 0.7874 0.4064)
			(stroke
				(width 0.1524)
				(type default)
			)
			(layer "F.SilkS")
		)
		(fp_line
			(start -0.7874 0.4064)
			(end -0.7874 -0.4064)
			(stroke
				(width 0.1524)
				(type default)
			)
			(layer "F.SilkS")
		)
		(fp_line
			(start -0.7874 -0.4064)
			(end 0.7874 -0.4064)
			(stroke
				(width 0.1524)
				(type default)
			)
			(layer "F.SilkS")
		)
		(fp_line
			(start 0.67945 0.3048)
			(end 0.120396 0.3048)
			(stroke
				(width 0.1)
				(type default)
			)
			(layer "F.Fab")
		)
		(fp_line
			(start 0.67945 -0.3048)
			(end 0.67945 0.3048)
			(stroke
				(width 0.1)
				(type default)
			)
			(layer "F.Fab")
		)
		(fp_line
			(start 0.12065 -0.2794)
			(end 0.12065 -0.3048)
			(stroke
				(width 0.1)
				(type default)
			)
			(layer "F.Fab")
		)
		(fp_line
			(start 0.12065 -0.3048)
			(end 0.67945 -0.3048)
			(stroke
				(width 0.1)
				(type default)
			)
			(layer "F.Fab")
		)
		(fp_line
			(start 0.120396 0.3048)
			(end 0.120396 0.2794)
			(stroke
				(width 0.1)
				(type default)
			)
			(layer "F.Fab")
		)
		(fp_line
			(start 0.120396 0.2794)
			(end -0.12065 0.2794)
			(stroke
				(width 0.1)
				(type default)
			)
			(layer "F.Fab")
		)
		(fp_line
			(start -0.12065 0.3048)
			(end -0.67945 0.3048)
			(stroke
				(width 0.1)
				(type default)
			)
			(layer "F.Fab")
		)
		(fp_line
			(start -0.12065 0.2794)
			(end -0.12065 0.3048)
			(stroke
				(width 0.1)
				(type default)
			)
			(layer "F.Fab")
		)
		(fp_line
			(start -0.12065 -0.2794)
			(end 0.12065 -0.2794)
			(stroke
				(width 0.1)
				(type default)
			)
			(layer "F.Fab")
		)
		(fp_line
			(start -0.12065 -0.305054)
			(end -0.12065 -0.2794)
			(stroke
				(width 0.1)
				(type default)
			)
			(layer "F.Fab")
		)
		(fp_line
			(start -0.67945 0.3048)
			(end -0.67945 -0.305054)
			(stroke
				(width 0.1)
				(type default)
			)
			(layer "F.Fab")
		)
		(fp_line
			(start -0.67945 -0.305054)
			(end -0.12065 -0.305054)
			(stroke
				(width 0.1)
				(type default)
			)
			(layer "F.Fab")
		)
		(pad "1" smd circle
			(at -0.40005 0 180)
			(size 0 0)
			(layers "F.Cu" "F.Mask" "F.Paste")
			(net "P12V_OCP_SFF_EN_R")
		)
		(pad "2" smd circle
			(at 0.40005 0 180)
			(size 0 0)
			(layers "F.Cu" "F.Mask" "F.Paste")
			(net "P12V_OCP_EN_1_R")
		)
	)
	(footprint ""
		(layer "F.Cu")
		(at 22.036278 -435.948074 180)
		(property "Reference" "R2991"
			(at 0 0 180)
			(layer "F.SilkS")
			(hide yes)
			(effects
				(font
					(size 1.27 1.27)
				)
			)
		)
		(property "Value" ""
			(at 0 0 180)
			(layer "F.Fab")
			(effects
				(font
					(size 1.27 1.27)
				)
			)
		)
		(duplicate_pad_numbers_are_jumpers no)
		(fp_line
			(start 0.7874 0.4064)
			(end -0.7874 0.4064)
			(stroke
				(width 0.1524)
				(type default)
			)
			(layer "F.SilkS")
		)
		(fp_line
			(start 0.7874 -0.4064)
			(end 0.7874 0.4064)
			(stroke
				(width 0.1524)
				(type default)
			)
			(layer "F.SilkS")
		)
		(fp_line
			(start -0.7874 0.4064)
			(end -0.7874 -0.4064)
			(stroke
				(width 0.1524)
				(type default)
			)
			(layer "F.SilkS")
		)
		(fp_line
			(start -0.7874 -0.4064)
			(end 0.7874 -0.4064)
			(stroke
				(width 0.1524)
				(type default)
			)
			(layer "F.SilkS")
		)
		(fp_line
			(start 0.67945 0.3048)
			(end 0.120396 0.3048)
			(stroke
				(width 0.1)
				(type default)
			)
			(layer "F.Fab")
		)
		(fp_line
			(start 0.67945 -0.3048)
			(end 0.67945 0.3048)
			(stroke
				(width 0.1)
				(type default)
			)
			(layer "F.Fab")
		)
		(fp_line
			(start 0.12065 -0.2794)
			(end 0.12065 -0.3048)
			(stroke
				(width 0.1)
				(type default)
			)
			(layer "F.Fab")
		)
		(fp_line
			(start 0.12065 -0.3048)
			(end 0.67945 -0.3048)
			(stroke
				(width 0.1)
				(type default)
			)
			(layer "F.Fab")
		)
		(fp_line
			(start 0.120396 0.3048)
			(end 0.120396 0.2794)
			(stroke
				(width 0.1)
				(type default)
			)
			(layer "F.Fab")
		)
		(fp_line
			(start 0.120396 0.2794)
			(end -0.12065 0.2794)
			(stroke
				(width 0.1)
				(type default)
			)
			(layer "F.Fab")
		)
		(fp_line
			(start -0.12065 0.3048)
			(end -0.67945 0.3048)
			(stroke
				(width 0.1)
				(type default)
			)
			(layer "F.Fab")
		)
		(fp_line
			(start -0.12065 0.2794)
			(end -0.12065 0.3048)
			(stroke
				(width 0.1)
				(type default)
			)
			(layer "F.Fab")
		)
		(fp_line
			(start -0.12065 -0.2794)
			(end 0.12065 -0.2794)
			(stroke
				(width 0.1)
				(type default)
			)
			(layer "F.Fab")
		)
		(fp_line
			(start -0.12065 -0.305054)
			(end -0.12065 -0.2794)
			(stroke
				(width 0.1)
				(type default)
			)
			(layer "F.Fab")
		)
		(fp_line
			(start -0.67945 0.3048)
			(end -0.67945 -0.305054)
			(stroke
				(width 0.1)
				(type default)
			)
			(layer "F.Fab")
		)
		(fp_line
			(start -0.67945 -0.305054)
			(end -0.12065 -0.305054)
			(stroke
				(width 0.1)
				(type default)
			)
			(layer "F.Fab")
		)
		(pad "1" smd circle
			(at -0.40005 0 180)
			(size 0 0)
			(layers "F.Cu" "F.Mask" "F.Paste")
			(net "SMB_2_BMC_GPU_BUF_R_SDA")
		)
		(pad "2" smd circle
			(at 0.40005 0 180)
			(size 0 0)
			(layers "F.Cu" "F.Mask" "F.Paste")
			(net "SMB_2_BMC_GPU_BUF_SDA")
		)
	)
)
